# TIMECARD (Time Appliance Project (Time Card)) — schematic netlist excerpt (pin names and nets, part order shuffled) for the footprints in the layout excerpt that follows; sources: Cadence DE-HDL packaged netlist, KiCad conversion of R4006-B0001-02_R01.brd

R379  RESISTOR  4.7KOHM 1%  pkg SMC_0402R_H016  page 23 : \1\ = XP3R3V_FPGA ; \2\ = SMA4_SIG_IN_BF_EN_N
R451  RESISTOR  1KOHM 1%  pkg SMC_0402R_H016  page 24 : \1\ = MUX1_SEL ; \2\ = SG

(kicad_pcb
	(version 20260206)
	(generator "pcbnew")
	(generator_version "10.0")
	(general
		(thickness 1.6)
		(legacy_teardrops no)
	)
	(paper "A4")
	(title_block
		(title "timecard-production-celestica-r4006 — R4006-B0001-02_R01.brd")
		(comment 1 "Time Appliance Project (Time Card) / footprints 1098-1099 of 1113")
	)
	(layers
		(0 "F.Cu" signal "TOP")
		(4 "In1.Cu" signal "L02_GND1")
		(6 "In2.Cu" signal "L03_SIG1")
		(8 "In3.Cu" signal "L04_GND2")
		(10 "In4.Cu" signal "L05_VCC1")
		(12 "In5.Cu" signal "L06_VCC2")
		(14 "In6.Cu" signal "L07_GND3")
		(16 "In7.Cu" signal "L08_SIG2")
		(18 "In8.Cu" signal "L09_GND4")
		(2 "B.Cu" signal "BOTTOM")
		(9 "F.Adhes" user "F.Adhesive")
		(11 "B.Adhes" user "B.Adhesive")
		(13 "F.Paste" user "Package Geometry/Pastemask Top")
		(15 "B.Paste" user "Package Geometry/Pastemask Bottom")
		(5 "F.SilkS" user "Ref Des/Silkscreen Top")
		(7 "B.SilkS" user "Ref Des/Silkscreen Bottom")
		(1 "F.Mask" user "Board Geometry/Soldermask Top")
		(3 "B.Mask" user "Board Geometry/Soldermask Bottom")
		(17 "Dwgs.User" user "User.Drawings")
		(19 "Cmts.User" user "User.Comments")
		(21 "Eco1.User" user "User.Eco1")
		(23 "Eco2.User" user "User.Eco2")
		(25 "Edge.Cuts" user "Board Geometry/Outline")
		(27 "Margin" user)
		(31 "F.CrtYd" user "Package Geometry/Place Bound Top")
		(29 "B.CrtYd" user "Package Geometry/Place Bound Bottom")
		(35 "F.Fab" user "Ref Des/Assembly Top")
		(33 "B.Fab" user "Ref Des/Assembly Bottom")
	)
	(footprint ""
		(layer "B.Cu")
		(at 14.6558 -17.1704 90)
		(property "Reference" "R379"
			(at 2.2606 -0.08255 270)
			(unlocked yes)
			(layer "B.SilkS")
			(effects
				(font
					(size 0.635 0.4064)
					(thickness 0.1524)
				)
				(justify mirror)
			)
		)
		(property "Value" "VAL*"
			(at -0.02032 2.13233 90)
			(unlocked yes)
			(layer "B.Fab")
			(hide yes)
			(effects
				(font
					(size 0.7874 0.5842)
					(thickness 0.1524)
				)
				(justify mirror)
			)
		)
		(property "Tolerance" "TOL*"
			(at -0.044704 3.05435 90)
			(unlocked yes)
			(layer "Cmts.User")
			(hide yes)
			(effects
				(font
					(size 0.7874 0.5842)
					(thickness 0.1524)
				)
				(justify mirror)
			)
		)
		(property "User Part Number" "PARTNUM*"
			(at -0.02032 4.024884 90)
			(unlocked yes)
			(layer "Cmts.User")
			(hide yes)
			(effects
				(font
					(size 0.7874 0.5842)
					(thickness 0.1524)
				)
				(justify mirror)
			)
		)
		(property "Device Type" "RESISTOR-G155-14701-01,4.7KOHMA"
			(at -0.008382 1.210564 90)
			(unlocked yes)
			(layer "B.Fab")
			(hide yes)
			(effects
				(font
					(size 0.7874 0.5842)
					(thickness 0.1524)
				)
				(justify mirror)
			)
		)
		(duplicate_pad_numbers_are_jumpers no)
		(fp_line
			(start 1.143 -0.5588)
			(end 1.143 0.5588)
			(stroke
				(width 0.1)
				(type default)
			)
			(layer "B.SilkS")
		)
		(fp_line
			(start -1.143 -0.5588)
			(end 1.143 -0.5588)
			(stroke
				(width 0.1)
				(type default)
			)
			(layer "B.SilkS")
		)
		(fp_line
			(start 1.143 0.5588)
			(end -1.143 0.5588)
			(stroke
				(width 0.1)
				(type default)
			)
			(layer "B.SilkS")
		)
		(fp_line
			(start -1.143 0.5588)
			(end -1.143 -0.5588)
			(stroke
				(width 0.1)
				(type default)
			)
			(layer "B.SilkS")
		)
		(fp_rect
			(start -1.143 0.5588)
			(end 1.143 -0.5588)
			(stroke
				(width 0)
				(type default)
			)
			(fill no)
			(layer "B.CrtYd")
		)
		(fp_line
			(start 0.508 -0.3048)
			(end 0.508 0.3048)
			(stroke
				(width 0.1)
				(type default)
			)
			(layer "B.Fab")
		)
		(fp_line
			(start -0.508 -0.3048)
			(end 0.508 -0.3048)
			(stroke
				(width 0.1)
				(type default)
			)
			(layer "B.Fab")
		)
		(fp_line
			(start 0.508 0.3048)
			(end -0.508 0.3048)
			(stroke
				(width 0.1)
				(type default)
			)
			(layer "B.Fab")
		)
		(fp_line
			(start -0.508 0.3048)
			(end -0.508 -0.3048)
			(stroke
				(width 0.1)
				(type default)
			)
			(layer "B.Fab")
		)
		(pad "1" smd rect
			(at 0.5334 0 270)
			(size 0.7112 0.6096)
			(layers "B.Cu" "B.Mask" "B.Paste")
			(net "XP3R3V_FPGA")
		)
		(pad "2" smd rect
			(at -0.5334 0 270)
			(size 0.7112 0.6096)
			(layers "B.Cu" "B.Mask" "B.Paste")
			(net "SMA4_SIG_IN_BF_EN_N")
		)
		(zone
			(layer "B.Cu")
			(hatch none 0.5)
			(connect_pads
				(clearance 0)
			)
			(min_thickness 0.25)
			(keepout
				(tracks allowed)
				(vias not_allowed)
				(pads allowed)
				(copperpour not_allowed)
				(footprints allowed)
			)
			(placement
				(enabled no)
				(sheetname "")
			)
			(fill
				(thermal_gap 0.5)
				(thermal_bridge_width 0.5)
				(island_removal_mode 0)
			)
			(polygon
				(pts
					(xy 14.9606 -17.0942) (xy 14.9606 -17.2466) (xy 14.351 -17.2466) (xy 14.351 -17.0942)
				)
			)
		)
		(zone
			(layer "B.Cu")
			(hatch none 0.5)
			(connect_pads
				(clearance 0)
			)
			(min_thickness 0.25)
			(keepout
				(tracks not_allowed)
				(vias allowed)
				(pads allowed)
				(copperpour not_allowed)
				(footprints allowed)
			)
			(placement
				(enabled no)
				(sheetname "")
			)
			(fill
				(thermal_gap 0.5)
				(thermal_bridge_width 0.5)
				(island_removal_mode 0)
			)
			(polygon
				(pts
					(xy 14.9606 -17.0942) (xy 14.9606 -17.2466) (xy 14.351 -17.2466) (xy 14.351 -17.0942)
				)
			)
		)
	)
	(footprint ""
		(layer "B.Cu")
		(at 98.044 -95.4532)
		(property "Reference" "R451"
			(at 2.667 0.11557 0)
			(unlocked yes)
			(layer "B.SilkS")
			(effects
				(font
					(size 0.7874 0.5842)
					(thickness 0.1524)
				)
				(justify mirror)
			)
		)
		(property "Value" "VAL*"
			(at -0.02032 2.13233 0)
			(unlocked yes)
			(layer "B.Fab")
			(hide yes)
			(effects
				(font
					(size 0.7874 0.5842)
					(thickness 0.1524)
				)
				(justify mirror)
			)
		)
		(property "Tolerance" "TOL*"
			(at -0.044704 3.05435 0)
			(unlocked yes)
			(layer "Cmts.User")
			(hide yes)
			(effects
				(font
					(size 0.7874 0.5842)
					(thickness 0.1524)
				)
				(justify mirror)
			)
		)
		(property "User Part Number" "PARTNUM*"
			(at -0.02032 4.024884 0)
			(unlocked yes)
			(layer "Cmts.User")
			(hide yes)
			(effects
				(font
					(size 0.7874 0.5842)
					(thickness 0.1524)
				)
				(justify mirror)
			)
		)
		(property "Device Type" "RESISTOR-G155-11001-01,1KOHM,1%"
			(at -0.008382 1.210564 0)
			(unlocked yes)
			(layer "B.Fab")
			(hide yes)
			(effects
				(font
					(size 0.7874 0.5842)
					(thickness 0.1524)
				)
				(justify mirror)
			)
		)
		(duplicate_pad_numbers_are_jumpers no)
		(fp_line
			(start -1.143 -0.5588)
			(end 1.143 -0.5588)
			(stroke
				(width 0.1)
				(type default)
			)
			(layer "B.SilkS")
		)
		(fp_line
			(start -1.143 0.5588)
			(end -1.143 -0.5588)
			(stroke
				(width 0.1)
				(type default)
			)
			(layer "B.SilkS")
		)
		(fp_line
			(start 1.143 -0.5588)
			(end 1.143 0.5588)
			(stroke
				(width 0.1)
				(type default)
			)
			(layer "B.SilkS")
		)
		(fp_line
			(start 1.143 0.5588)
			(end -1.143 0.5588)
			(stroke
				(width 0.1)
				(type default)
			)
			(layer "B.SilkS")
		)
		(fp_poly
			(pts
				(xy 1.143 0.5588) (xy -1.143 0.5588) (xy -1.143 -0.5588) (xy 1.143 -0.5588)
			)
			(stroke
				(width 0)
				(type default)
			)
			(fill no)
			(layer "B.CrtYd")
		)
		(fp_line
			(start -0.508 -0.3048)
			(end 0.508 -0.3048)
			(stroke
				(width 0.1)
				(type default)
			)
			(layer "B.Fab")
		)
		(fp_line
			(start -0.508 0.3048)
			(end -0.508 -0.3048)
			(stroke
				(width 0.1)
				(type default)
			)
			(layer "B.Fab")
		)
		(fp_line
			(start 0.508 -0.3048)
			(end 0.508 0.3048)
			(stroke
				(width 0.1)
				(type default)
			)
			(layer "B.Fab")
		)
		(fp_line
			(start 0.508 0.3048)
			(end -0.508 0.3048)
			(stroke
				(width 0.1)
				(type default)
			)
			(layer "B.Fab")
		)
		(pad "1" smd rect
			(at 0.5334 0 180)
			(size 0.7112 0.6096)
			(layers "B.Cu" "B.Mask" "B.Paste")
			(net "MUX1_SEL")
		)
		(pad "2" smd rect
			(at -0.5334 0 180)
			(size 0.7112 0.6096)
			(layers "B.Cu" "B.Mask" "B.Paste")
			(net "SG")
		)
		(zone
			(layer "B.Cu")
			(hatch none 0.5)
			(connect_pads
				(clearance 0)
			)
			(min_thickness 0.25)
			(keepout
				(tracks not_allowed)
				(vias allowed)
				(pads allowed)
				(copperpour not_allowed)
				(footprints allowed)
			)
			(placement
				(enabled no)
				(sheetname "")
			)
			(fill
				(thermal_gap 0.5)
				(thermal_bridge_width 0.5)
				(island_removal_mode 0)
			)
			(polygon
				(pts
					(xy 98.1202 -95.1484) (xy 98.1202 -95.758) (xy 97.9678 -95.758) (xy 97.9678 -95.1484)
				)
			)
		)
		(zone
			(layer "B.Cu")
			(hatch none 0.5)
			(connect_pads
				(clearance 0)
			)
			(min_thickness 0.25)
			(keepout
				(tracks allowed)
				(vias not_allowed)
				(pads allowed)
				(copperpour not_allowed)
				(footprints allowed)
			)
			(placement
				(enabled no)
				(sheetname "")
			)
			(fill
				(thermal_gap 0.5)
				(thermal_bridge_width 0.5)
				(island_removal_mode 0)
			)
			(polygon
				(pts
					(xy 98.1202 -95.1484) (xy 98.1202 -95.758) (xy 97.9678 -95.758) (xy 97.9678 -95.1484)
				)
			)
		)
	)
)
